(kicad_pcb
	(version 20260206)
	(generator "pcbnew")
	(generator_version "10.0")
	(general
		(thickness 1.6)
		(legacy_teardrops no)
	)
	(paper "A4")
	(title_block
		(title "01162023_DA0F0TEBIF0_F0T_Expander_BD_F_brd_V02_OCP.brd")
		(comment 1 "Grand Teton / footprints 1-6 of 9728")
	)
	(layers
		(0 "F.Cu" signal "TOP")
		(4 "In1.Cu" signal "GND")
		(6 "In2.Cu" signal "VCC")
		(8 "In3.Cu" signal "VCC1")
		(10 "In4.Cu" signal "GND1")
		(12 "In5.Cu" signal "IN1")
		(14 "In6.Cu" signal "GND2")
		(16 "In7.Cu" signal "IN2")
		(18 "In8.Cu" signal "GND3")
		(20 "In9.Cu" signal "IN3")
		(22 "In10.Cu" signal "GND4")
		(24 "In11.Cu" signal "IN4")
		(26 "In12.Cu" signal "GND5")
		(28 "In13.Cu" signal "IN5")
		(30 "In14.Cu" signal "GND6")
		(32 "In15.Cu" signal "IN6")
		(34 "In16.Cu" signal "GND7")
		(2 "B.Cu" signal "BOTTOM")
		(9 "F.Adhes" user "F.Adhesive")
		(11 "B.Adhes" user "B.Adhesive")
		(13 "F.Paste" user "Package Geometry/Pastemask Top")
		(15 "B.Paste" user "Package Geometry/Pastemask Bottom")
		(5 "F.SilkS" user "Ref Des/Silkscreen Top")
		(7 "B.SilkS" user "Ref Des/Silkscreen Bottom")
		(1 "F.Mask" user "Board Geometry/Soldermask Top")
		(3 "B.Mask" user "Board Geometry/Soldermask Bottom")
		(17 "Dwgs.User" user "User.Drawings")
		(19 "Cmts.User" user "User.Comments")
		(21 "Eco1.User" user "User.Eco1")
		(23 "Eco2.User" user "User.Eco2")
		(25 "Edge.Cuts" user "Board Geometry/Outline")
		(27 "Margin" user)
		(31 "F.CrtYd" user "Package Geometry/Place Bound Top")
		(29 "B.CrtYd" user "Package Geometry/Place Bound Bottom")
		(35 "F.Fab" user "Ref Des/Assembly Top")
		(33 "B.Fab" user "Ref Des/Assembly Bottom")
	)
	(footprint ""
		(layer "F.Cu")
		(at 22.027896 -35.876738)
		(property "Reference" "R5871"
			(at 0 0 0)
			(layer "F.SilkS")
			(hide yes)
			(effects
				(font
					(size 1.27 1.27)
				)
			)
		)
		(property "Value" ""
			(at 0 0 0)
			(layer "F.Fab")
			(effects
				(font
					(size 1.27 1.27)
				)
			)
		)
		(duplicate_pad_numbers_are_jumpers no)
		(fp_line
			(start -0.7874 -0.4064)
			(end 0.7874 -0.4064)
			(stroke
				(width 0.1524)
				(type default)
			)
			(layer "F.SilkS")
		)
		(fp_line
			(start -0.7874 0.4064)
			(end -0.7874 -0.4064)
			(stroke
				(width 0.1524)
				(type default)
			)
			(layer "F.SilkS")
		)
		(fp_line
			(start 0.7874 -0.4064)
			(end 0.7874 0.4064)
			(stroke
				(width 0.1524)
				(type default)
			)
			(layer "F.SilkS")
		)
		(fp_line
			(start 0.7874 0.4064)
			(end -0.7874 0.4064)
			(stroke
				(width 0.1524)
				(type default)
			)
			(layer "F.SilkS")
		)
		(fp_line
			(start -0.67945 -0.305054)
			(end -0.12065 -0.305054)
			(stroke
				(width 0.1)
				(type default)
			)
			(layer "F.Fab")
		)
		(fp_line
			(start -0.67945 0.3048)
			(end -0.67945 -0.305054)
			(stroke
				(width 0.1)
				(type default)
			)
			(layer "F.Fab")
		)
		(fp_line
			(start -0.12065 -0.305054)
			(end -0.12065 -0.2794)
			(stroke
				(width 0.1)
				(type default)
			)
			(layer "F.Fab")
		)
		(fp_line
			(start -0.12065 -0.2794)
			(end 0.12065 -0.2794)
			(stroke
				(width 0.1)
				(type default)
			)
			(layer "F.Fab")
		)
		(fp_line
			(start -0.12065 0.2794)
			(end -0.12065 0.3048)
			(stroke
				(width 0.1)
				(type default)
			)
			(layer "F.Fab")
		)
		(fp_line
			(start -0.12065 0.3048)
			(end -0.67945 0.3048)
			(stroke
				(width 0.1)
				(type default)
			)
			(layer "F.Fab")
		)
		(fp_line
			(start 0.120396 0.2794)
			(end -0.12065 0.2794)
			(stroke
				(width 0.1)
				(type default)
			)
			(layer "F.Fab")
		)
		(fp_line
			(start 0.120396 0.3048)
			(end 0.120396 0.2794)
			(stroke
				(width 0.1)
				(type default)
			)
			(layer "F.Fab")
		)
		(fp_line
			(start 0.12065 -0.3048)
			(end 0.67945 -0.3048)
			(stroke
				(width 0.1)
				(type default)
			)
			(layer "F.Fab")
		)
		(fp_line
			(start 0.12065 -0.2794)
			(end 0.12065 -0.3048)
			(stroke
				(width 0.1)
				(type default)
			)
			(layer "F.Fab")
		)
		(fp_line
			(start 0.67945 -0.3048)
			(end 0.67945 0.3048)
			(stroke
				(width 0.1)
				(type default)
			)
			(layer "F.Fab")
		)
		(fp_line
			(start 0.67945 0.3048)
			(end 0.120396 0.3048)
			(stroke
				(width 0.1)
				(type default)
			)
			(layer "F.Fab")
		)
		(pad "1" smd circle
			(at -0.40005 0)
			(size 0 0)
			(layers "F.Cu" "F.Mask" "F.Paste")
			(net "PWRGD_P3V3_SSD1_D")
		)
		(pad "2" smd circle
			(at 0.40005 0)
			(size 0 0)
			(layers "F.Cu" "F.Mask" "F.Paste")
			(net "PWRGD_P3V3_SSD1_R")
		)
	)
	(footprint ""
		(layer "F.Cu")
		(at 242.349782 -148.872702)
		(property "Reference" "PD94"
			(at -3.4544 -2.225548 0)
			(unlocked yes)
			(layer "F.SilkS")
			(effects
				(font
					(size 0.7874 0.5842)
					(thickness 0.1524)
				)
				(justify left)
			)
		)
		(property "Value" ""
			(at 0 0 0)
			(layer "F.Fab")
			(effects
				(font
					(size 1.27 1.27)
				)
			)
		)
		(duplicate_pad_numbers_are_jumpers no)
		(fp_line
			(start -3.400044 -1.459992)
			(end 4.107942 -1.459992)
			(stroke
				(width 0.1524)
				(type default)
			)
			(layer "F.SilkS")
		)
		(fp_line
			(start -3.400044 1.459992)
			(end -3.400044 -1.459992)
			(stroke
				(width 0.1524)
				(type default)
			)
			(layer "F.SilkS")
		)
		(fp_line
			(start 4.107942 -1.459992)
			(end 4.107942 1.459992)
			(stroke
				(width 0.1524)
				(type default)
			)
			(layer "F.SilkS")
		)
		(fp_line
			(start 4.107942 1.459992)
			(end -3.400044 1.459992)
			(stroke
				(width 0.1524)
				(type default)
			)
			(layer "F.SilkS")
		)
		(fp_poly
			(pts
				(xy 4.107942 -1.459992) (xy 4.107942 1.459992) (xy 3.308096 1.459992) (xy 3.308096 -1.459992)
			)
			(stroke
				(width 0)
				(type default)
			)
			(fill yes)
			(layer "F.SilkS")
		)
		(fp_line
			(start -2.29997 -1.459992)
			(end 2.29997 -1.459992)
			(stroke
				(width 0.1)
				(type default)
			)
			(layer "F.Fab")
		)
		(fp_line
			(start -2.29997 1.459992)
			(end -2.29997 -1.459992)
			(stroke
				(width 0.1)
				(type default)
			)
			(layer "F.Fab")
		)
		(fp_line
			(start 2.29997 -1.459992)
			(end 2.29997 1.459992)
			(stroke
				(width 0.1)
				(type default)
			)
			(layer "F.Fab")
		)
		(fp_line
			(start 2.29997 1.459992)
			(end -2.29997 1.459992)
			(stroke
				(width 0.1)
				(type default)
			)
			(layer "F.Fab")
		)
		(fp_text user "+"
			(at -4.7752 -0.12065 0)
			(unlocked yes)
			(layer "F.SilkS")
			(effects
				(font
					(size 1.905 1.4224)
					(thickness 0.1524)
				)
				(justify left)
			)
		)
		(fp_text user "-"
			(at 5.4102 0.29845 180)
			(unlocked yes)
			(layer "F.SilkS")
			(effects
				(font
					(size 1.905 1.4224)
					(thickness 0.1524)
				)
				(justify left)
			)
		)
		(fp_text user "+"
			(at -4.7752 -0.12065 0)
			(unlocked yes)
			(layer "F.Fab")
			(effects
				(font
					(size 1.905 1.4224)
					(thickness 0.1524)
				)
				(justify left)
			)
		)
		(fp_text user "-"
			(at 5.4102 0.29845 180)
			(unlocked yes)
			(layer "F.Fab")
			(effects
				(font
					(size 1.905 1.4224)
					(thickness 0.1524)
				)
				(justify left)
			)
		)
		(pad "A" smd rect
			(at -1.999996 0 90)
			(size 1.7018 2.5146)
			(layers "F.Cu" "F.Mask" "F.Paste")
			(net "GND")
		)
		(pad "C" smd rect
			(at 1.999996 0 90)
			(size 1.7018 2.5146)
			(layers "F.Cu" "F.Mask" "F.Paste")
			(net "P12V_NIC4_R")
		)
	)
	(footprint ""
		(layer "F.Cu")
		(at 7.856728 -45.071792 180)
		(property "Reference" "R5539"
			(at 0 0 180)
			(layer "F.SilkS")
			(hide yes)
			(effects
				(font
					(size 1.27 1.27)
				)
			)
		)
		(property "Value" ""
			(at 0 0 180)
			(layer "F.Fab")
			(effects
				(font
					(size 1.27 1.27)
				)
			)
		)
		(duplicate_pad_numbers_are_jumpers no)
		(fp_line
			(start 0.7874 0.4064)
			(end -0.7874 0.4064)
			(stroke
				(width 0.1524)
				(type default)
			)
			(layer "F.SilkS")
		)
		(fp_line
			(start 0.7874 -0.4064)
			(end 0.7874 0.4064)
			(stroke
				(width 0.1524)
				(type default)
			)
			(layer "F.SilkS")
		)
		(fp_line
			(start -0.7874 0.4064)
			(end -0.7874 -0.4064)
			(stroke
				(width 0.1524)
				(type default)
			)
			(layer "F.SilkS")
		)
		(fp_line
			(start -0.7874 -0.4064)
			(end 0.7874 -0.4064)
			(stroke
				(width 0.1524)
				(type default)
			)
			(layer "F.SilkS")
		)
		(fp_line
			(start 0.67945 0.3048)
			(end 0.120396 0.3048)
			(stroke
				(width 0.1)
				(type default)
			)
			(layer "F.Fab")
		)
		(fp_line
			(start 0.67945 -0.3048)
			(end 0.67945 0.3048)
			(stroke
				(width 0.1)
				(type default)
			)
			(layer "F.Fab")
		)
		(fp_line
			(start 0.12065 -0.2794)
			(end 0.12065 -0.3048)
			(stroke
				(width 0.1)
				(type default)
			)
			(layer "F.Fab")
		)
		(fp_line
			(start 0.12065 -0.3048)
			(end 0.67945 -0.3048)
			(stroke
				(width 0.1)
				(type default)
			)
			(layer "F.Fab")
		)
		(fp_line
			(start 0.120396 0.3048)
			(end 0.120396 0.2794)
			(stroke
				(width 0.1)
				(type default)
			)
			(layer "F.Fab")
		)
		(fp_line
			(start 0.120396 0.2794)
			(end -0.12065 0.2794)
			(stroke
				(width 0.1)
				(type default)
			)
			(layer "F.Fab")
		)
		(fp_line
			(start -0.12065 0.3048)
			(end -0.67945 0.3048)
			(stroke
				(width 0.1)
				(type default)
			)
			(layer "F.Fab")
		)
		(fp_line
			(start -0.12065 0.2794)
			(end -0.12065 0.3048)
			(stroke
				(width 0.1)
				(type default)
			)
			(layer "F.Fab")
		)
		(fp_line
			(start -0.12065 -0.2794)
			(end 0.12065 -0.2794)
			(stroke
				(width 0.1)
				(type default)
			)
			(layer "F.Fab")
		)
		(fp_line
			(start -0.12065 -0.305054)
			(end -0.12065 -0.2794)
			(stroke
				(width 0.1)
				(type default)
			)
			(layer "F.Fab")
		)
		(fp_line
			(start -0.67945 0.3048)
			(end -0.67945 -0.305054)
			(stroke
				(width 0.1)
				(type default)
			)
			(layer "F.Fab")
		)
		(fp_line
			(start -0.67945 -0.305054)
			(end -0.12065 -0.305054)
			(stroke
				(width 0.1)
				(type default)
			)
			(layer "F.Fab")
		)
		(pad "1" smd circle
			(at -0.40005 0 180)
			(size 0 0)
			(layers "F.Cu" "F.Mask" "F.Paste")
			(net "PRSNT_SSD0_R1_N")
		)
		(pad "2" smd circle
			(at 0.40005 0 180)
			(size 0 0)
			(layers "F.Cu" "F.Mask" "F.Paste")
			(net "PRSNT_SSD0_R_N")
		)
	)
	(footprint ""
		(layer "F.Cu")
		(at 204.591158 -81.627472)
		(property "Reference" "R4333"
			(at 0 0 0)
			(layer "F.SilkS")
			(hide yes)
			(effects
				(font
					(size 1.27 1.27)
				)
			)
		)
		(property "Value" ""
			(at 0 0 0)
			(layer "F.Fab")
			(effects
				(font
					(size 1.27 1.27)
				)
			)
		)
		(duplicate_pad_numbers_are_jumpers no)
		(fp_line
			(start -0.7874 -0.4064)
			(end 0.7874 -0.4064)
			(stroke
				(width 0.1524)
				(type default)
			)
			(layer "F.SilkS")
		)
		(fp_line
			(start -0.7874 0.4064)
			(end -0.7874 -0.4064)
			(stroke
				(width 0.1524)
				(type default)
			)
			(layer "F.SilkS")
		)
		(fp_line
			(start 0.7874 -0.4064)
			(end 0.7874 0.4064)
			(stroke
				(width 0.1524)
				(type default)
			)
			(layer "F.SilkS")
		)
		(fp_line
			(start 0.7874 0.4064)
			(end -0.7874 0.4064)
			(stroke
				(width 0.1524)
				(type default)
			)
			(layer "F.SilkS")
		)
		(fp_line
			(start -0.67945 -0.305054)
			(end -0.12065 -0.305054)
			(stroke
				(width 0.1)
				(type default)
			)
			(layer "F.Fab")
		)
		(fp_line
			(start -0.67945 0.3048)
			(end -0.67945 -0.305054)
			(stroke
				(width 0.1)
				(type default)
			)
			(layer "F.Fab")
		)
		(fp_line
			(start -0.12065 -0.305054)
			(end -0.12065 -0.2794)
			(stroke
				(width 0.1)
				(type default)
			)
			(layer "F.Fab")
		)
		(fp_line
			(start -0.12065 -0.2794)
			(end 0.12065 -0.2794)
			(stroke
				(width 0.1)
				(type default)
			)
			(layer "F.Fab")
		)
		(fp_line
			(start -0.12065 0.2794)
			(end -0.12065 0.3048)
			(stroke
				(width 0.1)
				(type default)
			)
			(layer "F.Fab")
		)
		(fp_line
			(start -0.12065 0.3048)
			(end -0.67945 0.3048)
			(stroke
				(width 0.1)
				(type default)
			)
			(layer "F.Fab")
		)
		(fp_line
			(start 0.120396 0.2794)
			(end -0.12065 0.2794)
			(stroke
				(width 0.1)
				(type default)
			)
			(layer "F.Fab")
		)
		(fp_line
			(start 0.120396 0.3048)
			(end 0.120396 0.2794)
			(stroke
				(width 0.1)
				(type default)
			)
			(layer "F.Fab")
		)
		(fp_line
			(start 0.12065 -0.3048)
			(end 0.67945 -0.3048)
			(stroke
				(width 0.1)
				(type default)
			)
			(layer "F.Fab")
		)
		(fp_line
			(start 0.12065 -0.2794)
			(end 0.12065 -0.3048)
			(stroke
				(width 0.1)
				(type default)
			)
			(layer "F.Fab")
		)
		(fp_line
			(start 0.67945 -0.3048)
			(end 0.67945 0.3048)
			(stroke
				(width 0.1)
				(type default)
			)
			(layer "F.Fab")
		)
		(fp_line
			(start 0.67945 0.3048)
			(end 0.120396 0.3048)
			(stroke
				(width 0.1)
				(type default)
			)
			(layer "F.Fab")
		)
		(pad "1" smd circle
			(at -0.40005 0)
			(size 0 0)
			(layers "F.Cu" "F.Mask" "F.Paste")
			(net "P3V3_AUX")
		)
		(pad "2" smd circle
			(at 0.40005 0)
			(size 0 0)
			(layers "F.Cu" "F.Mask" "F.Paste")
			(net "SSD3_LED_R")
		)
	)
	(footprint ""
		(layer "F.Cu")
		(at 97.796096 -47.20082 90)
		(property "Reference" "C211"
			(at 0 0 90)
			(layer "F.SilkS")
			(hide yes)
			(effects
				(font
					(size 1.27 1.27)
				)
			)
		)
		(property "Value" ""
			(at 0 0 90)
			(layer "F.Fab")
			(effects
				(font
					(size 1.27 1.27)
				)
			)
		)
		(duplicate_pad_numbers_are_jumpers no)
		(fp_line
			(start 0.7874 -0.4064)
			(end 0.7874 0.4064)
			(stroke
				(width 0.1524)
				(type default)
			)
			(layer "F.SilkS")
		)
		(fp_line
			(start -0.7874 -0.4064)
			(end 0.7874 -0.4064)
			(stroke
				(width 0.1524)
				(type default)
			)
			(layer "F.SilkS")
		)
		(fp_line
			(start 0.7874 0.4064)
			(end -0.7874 0.4064)
			(stroke
				(width 0.1524)
				(type default)
			)
			(layer "F.SilkS")
		)
		(fp_line
			(start -0.7874 0.4064)
			(end -0.7874 -0.4064)
			(stroke
				(width 0.1524)
				(type default)
			)
			(layer "F.SilkS")
		)
		(fp_line
			(start -0.12065 -0.305054)
			(end -0.12065 -0.2794)
			(stroke
				(width 0.1)
				(type default)
			)
			(layer "F.Fab")
		)
		(fp_line
			(start -0.67945 -0.305054)
			(end -0.12065 -0.305054)
			(stroke
				(width 0.1)
				(type default)
			)
			(layer "F.Fab")
		)
		(fp_line
			(start 0.67945 -0.3048)
			(end 0.67945 0.3048)
			(stroke
				(width 0.1)
				(type default)
			)
			(layer "F.Fab")
		)
		(fp_line
			(start 0.12065 -0.3048)
			(end 0.67945 -0.3048)
			(stroke
				(width 0.1)
				(type default)
			)
			(layer "F.Fab")
		)
		(fp_line
			(start 0.12065 -0.2794)
			(end 0.12065 -0.3048)
			(stroke
				(width 0.1)
				(type default)
			)
			(layer "F.Fab")
		)
		(fp_line
			(start -0.12065 -0.2794)
			(end 0.12065 -0.2794)
			(stroke
				(width 0.1)
				(type default)
			)
			(layer "F.Fab")
		)
		(fp_line
			(start 0.120396 0.2794)
			(end -0.12065 0.2794)
			(stroke
				(width 0.1)
				(type default)
			)
			(layer "F.Fab")
		)
		(fp_line
			(start -0.12065 0.2794)
			(end -0.12065 0.3048)
			(stroke
				(width 0.1)
				(type default)
			)
			(layer "F.Fab")
		)
		(fp_line
			(start 0.67945 0.3048)
			(end 0.120396 0.3048)
			(stroke
				(width 0.1)
				(type default)
			)
			(layer "F.Fab")
		)
		(fp_line
			(start 0.120396 0.3048)
			(end 0.120396 0.2794)
			(stroke
				(width 0.1)
				(type default)
			)
			(layer "F.Fab")
		)
		(fp_line
			(start -0.12065 0.3048)
			(end -0.67945 0.3048)
			(stroke
				(width 0.1)
				(type default)
			)
			(layer "F.Fab")
		)
		(fp_line
			(start -0.67945 0.3048)
			(end -0.67945 -0.305054)
			(stroke
				(width 0.1)
				(type default)
			)
			(layer "F.Fab")
		)
		(pad "1" smd circle
			(at -0.40005 0 90)
			(size 0 0)
			(layers "F.Cu" "F.Mask" "F.Paste")
			(net "P12V_SSD3_R")
		)
		(pad "2" smd circle
			(at 0.40005 0 90)
			(size 0 0)
			(layers "F.Cu" "F.Mask" "F.Paste")
			(net "GND")
		)
	)
	(footprint ""
		(layer "F.Cu")
		(at 215.075516 -118.207028 180)
		(property "Reference" "R884"
			(at 0 0 180)
			(layer "F.SilkS")
			(hide yes)
			(effects
				(font
					(size 1.27 1.27)
				)
			)
		)
		(property "Value" ""
			(at 0 0 180)
			(layer "F.Fab")
			(effects
				(font
					(size 1.27 1.27)
				)
			)
		)
		(duplicate_pad_numbers_are_jumpers no)
		(fp_line
			(start 0.7874 0.4064)
			(end -0.7874 0.4064)
			(stroke
				(width 0.1524)
				(type default)
			)
			(layer "F.SilkS")
		)
		(fp_line
			(start 0.7874 -0.4064)
			(end 0.7874 0.4064)
			(stroke
				(width 0.1524)
				(type default)
			)
			(layer "F.SilkS")
		)
		(fp_line
			(start -0.7874 0.4064)
			(end -0.7874 -0.4064)
			(stroke
				(width 0.1524)
				(type default)
			)
			(layer "F.SilkS")
		)
		(fp_line
			(start -0.7874 -0.4064)
			(end 0.7874 -0.4064)
			(stroke
				(width 0.1524)
				(type default)
			)
			(layer "F.SilkS")
		)
		(fp_line
			(start 0.67945 0.3048)
			(end 0.120396 0.3048)
			(stroke
				(width 0.1)
				(type default)
			)
			(layer "F.Fab")
		)
		(fp_line
			(start 0.67945 -0.3048)
			(end 0.67945 0.3048)
			(stroke
				(width 0.1)
				(type default)
			)
			(layer "F.Fab")
		)
		(fp_line
			(start 0.12065 -0.2794)
			(end 0.12065 -0.3048)
			(stroke
				(width 0.1)
				(type default)
			)
			(layer "F.Fab")
		)
		(fp_line
			(start 0.12065 -0.3048)
			(end 0.67945 -0.3048)
			(stroke
				(width 0.1)
				(type default)
			)
			(layer "F.Fab")
		)
		(fp_line
			(start 0.120396 0.3048)
			(end 0.120396 0.2794)
			(stroke
				(width 0.1)
				(type default)
			)
			(layer "F.Fab")
		)
		(fp_line
			(start 0.120396 0.2794)
			(end -0.12065 0.2794)
			(stroke
				(width 0.1)
				(type default)
			)
			(layer "F.Fab")
		)
		(fp_line
			(start -0.12065 0.3048)
			(end -0.67945 0.3048)
			(stroke
				(width 0.1)
				(type default)
			)
			(layer "F.Fab")
		)
		(fp_line
			(start -0.12065 0.2794)
			(end -0.12065 0.3048)
			(stroke
				(width 0.1)
				(type default)
			)
			(layer "F.Fab")
		)
		(fp_line
			(start -0.12065 -0.2794)
			(end 0.12065 -0.2794)
			(stroke
				(width 0.1)
				(type default)
			)
			(layer "F.Fab")
		)
		(fp_line
			(start -0.12065 -0.305054)
			(end -0.12065 -0.2794)
			(stroke
				(width 0.1)
				(type default)
			)
			(layer "F.Fab")
		)
		(fp_line
			(start -0.67945 0.3048)
			(end -0.67945 -0.305054)
			(stroke
				(width 0.1)
				(type default)
			)
			(layer "F.Fab")
		)
		(fp_line
			(start -0.67945 -0.305054)
			(end -0.12065 -0.305054)
			(stroke
				(width 0.1)
				(type default)
			)
			(layer "F.Fab")
		)
		(pad "1" smd circle
			(at -0.40005 0 180)
			(size 0 0)
			(layers "F.Cu" "F.Mask" "F.Paste")
			(net "P3V3_NIC3")
		)
		(pad "2" smd circle
			(at 0.40005 0 180)
			(size 0 0)
			(layers "F.Cu" "F.Mask" "F.Paste")
			(net "PWRGD_P3V3_NIC3")
		)
	)
)
